(kicad_pcb
	(version 20260206)
	(generator "pcbnew")
	(generator_version "10.0")
	(general
		(thickness 1.6)
		(legacy_teardrops no)
	)
	(paper "A4")
	(title_block
		(title "panther-plus-userver — 13130-1b_20150205.brd")
		(comment 1 "Honey Badger (Wiwynn) / footprints 919-926 of 1509")
	)
	(layers
		(0 "F.Cu" signal "TOP")
		(4 "In1.Cu" signal "L2")
		(6 "In2.Cu" signal "L3")
		(8 "In3.Cu" signal "L4")
		(10 "In4.Cu" signal "L5")
		(12 "In5.Cu" signal "L6")
		(14 "In6.Cu" signal "L7")
		(16 "In7.Cu" signal "L8")
		(18 "In8.Cu" signal "L9")
		(20 "In9.Cu" signal "L10")
		(22 "In10.Cu" signal "L11")
		(2 "B.Cu" signal "BOTTOM")
		(9 "F.Adhes" user "F.Adhesive")
		(11 "B.Adhes" user "B.Adhesive")
		(13 "F.Paste" user "Package Geometry/Pastemask Top")
		(15 "B.Paste" user "Package Geometry/Pastemask Bottom")
		(5 "F.SilkS" user "Ref Des/Silkscreen Top")
		(7 "B.SilkS" user "Ref Des/Silkscreen Bottom")
		(1 "F.Mask" user "Board Geometry/Soldermask Top")
		(3 "B.Mask" user "Board Geometry/Soldermask Bottom")
		(17 "Dwgs.User" user "User.Drawings")
		(19 "Cmts.User" user "User.Comments")
		(21 "Eco1.User" user "User.Eco1")
		(23 "Eco2.User" user "User.Eco2")
		(25 "Edge.Cuts" user "Board Geometry/Outline")
		(27 "Margin" user)
		(31 "F.CrtYd" user "Package Geometry/Place Bound Top")
		(29 "B.CrtYd" user "Package Geometry/Place Bound Bottom")
		(35 "F.Fab" user "Ref Des/Assembly Top")
		(33 "B.Fab" user "Ref Des/Assembly Bottom")
	)
	(footprint ""
		(layer "B.Cu")
		(at 87.503 -34.9504 180)
		(property "Reference" "R337"
			(at 0 0 0)
			(layer "B.SilkS")
			(hide yes)
			(effects
				(font
					(size 1.27 1.27)
				)
				(justify mirror)
			)
		)
		(property "Value" "0R2J-2-GP"
			(at -1.7907 -1.1176 180)
			(unlocked yes)
			(layer "B.Fab")
			(hide yes)
			(effects
				(font
					(size 1.016 1.016)
					(thickness 0.1524)
				)
				(justify mirror)
			)
		)
		(property "Device Type" "R402H16"
			(at -1.7907 -2.6416 180)
			(unlocked yes)
			(layer "B.Fab")
			(hide yes)
			(effects
				(font
					(size 1.016 1.016)
					(thickness 0.1524)
				)
				(justify mirror)
			)
		)
		(duplicate_pad_numbers_are_jumpers no)
		(fp_rect
			(start 0.381 0.8382)
			(end -0.381 -0.8382)
			(stroke
				(width 0)
				(type default)
			)
			(fill no)
			(layer "B.CrtYd")
		)
		(fp_rect
			(start 0.381 0.8382)
			(end -0.381 -0.8382)
			(stroke
				(width 0)
				(type default)
			)
			(fill no)
			(layer "B.Fab")
		)
		(pad "1" smd custom
			(at 0 -0.4318)
			(size 0.127 0.127)
			(layers "B.Cu" "B.Mask" "B.Paste")
			(net "PMU_SLP_DDRVTT#")
			(options
				(clearance outline)
				(anchor circle)
			)
			(primitives
				(gr_poly
					(pts
						(arc
							(start -0.2032 0.2794)
							(mid -0.239121 0.264521)
							(end -0.254 0.2286)
						)
						(arc
							(start -0.254 -0.2286)
							(mid -0.239121 -0.264521)
							(end -0.2032 -0.2794)
						)
						(arc
							(start 0.2032 -0.2794)
							(mid 0.239121 -0.264521)
							(end 0.254 -0.2286)
						)
						(arc
							(start 0.254 0.2286)
							(mid 0.239121 0.264521)
							(end 0.2032 0.2794)
						)
					)
					(width 0)
					(fill yes)
				)
			)
		)
		(pad "2" smd custom
			(at 0 0.4318)
			(size 0.127 0.127)
			(layers "B.Cu" "B.Mask" "B.Paste")
			(net "PMU_SLP_LAN#")
			(options
				(clearance outline)
				(anchor circle)
			)
			(primitives
				(gr_poly
					(pts
						(arc
							(start -0.2032 0.2794)
							(mid -0.239121 0.264521)
							(end -0.254 0.2286)
						)
						(arc
							(start -0.254 -0.2286)
							(mid -0.239121 -0.264521)
							(end -0.2032 -0.2794)
						)
						(arc
							(start 0.2032 -0.2794)
							(mid 0.239121 -0.264521)
							(end 0.254 -0.2286)
						)
						(arc
							(start 0.254 0.2286)
							(mid 0.239121 0.264521)
							(end 0.2032 0.2794)
						)
					)
					(width 0)
					(fill yes)
				)
			)
		)
	)
	(footprint ""
		(layer "B.Cu")
		(at 49.53 -43.434 180)
		(property "Reference" "R95"
			(at 0 0 0)
			(layer "B.SilkS")
			(hide yes)
			(effects
				(font
					(size 1.27 1.27)
				)
				(justify mirror)
			)
		)
		(property "Value" "4K7R2F-GP"
			(at -0.064008 -3.993896 180)
			(unlocked yes)
			(layer "B.Fab")
			(hide yes)
			(effects
				(font
					(size 1.016 1.016)
					(thickness 0.1524)
				)
				(justify mirror)
			)
		)
		(property "Device Type" "R402H16"
			(at -0.064008 -5.517896 180)
			(unlocked yes)
			(layer "B.Fab")
			(hide yes)
			(effects
				(font
					(size 1.016 1.016)
					(thickness 0.1524)
				)
				(justify mirror)
			)
		)
		(duplicate_pad_numbers_are_jumpers no)
		(fp_rect
			(start 0.381 0.8382)
			(end -0.381 -0.8382)
			(stroke
				(width 0)
				(type default)
			)
			(fill no)
			(layer "B.CrtYd")
		)
		(fp_rect
			(start 0.381 0.8382)
			(end -0.381 -0.8382)
			(stroke
				(width 0)
				(type default)
			)
			(fill no)
			(layer "B.Fab")
		)
		(pad "1" smd custom
			(at 0 -0.4318)
			(size 0.127 0.127)
			(layers "B.Cu" "B.Mask" "B.Paste")
			(net "P3V3_STBY")
			(options
				(clearance outline)
				(anchor circle)
			)
			(primitives
				(gr_poly
					(pts
						(arc
							(start -0.2032 0.2794)
							(mid -0.239121 0.264521)
							(end -0.254 0.2286)
						)
						(arc
							(start -0.254 -0.2286)
							(mid -0.239121 -0.264521)
							(end -0.2032 -0.2794)
						)
						(arc
							(start 0.2032 -0.2794)
							(mid 0.239121 -0.264521)
							(end 0.254 -0.2286)
						)
						(arc
							(start 0.254 0.2286)
							(mid 0.239121 0.264521)
							(end 0.2032 0.2794)
						)
					)
					(width 0)
					(fill yes)
				)
			)
		)
		(pad "2" smd custom
			(at 0 0.4318)
			(size 0.127 0.127)
			(layers "B.Cu" "B.Mask" "B.Paste")
			(net "CLKGEN_DIF_STOP#")
			(options
				(clearance outline)
				(anchor circle)
			)
			(primitives
				(gr_poly
					(pts
						(arc
							(start -0.2032 0.2794)
							(mid -0.239121 0.264521)
							(end -0.254 0.2286)
						)
						(arc
							(start -0.254 -0.2286)
							(mid -0.239121 -0.264521)
							(end -0.2032 -0.2794)
						)
						(arc
							(start 0.2032 -0.2794)
							(mid 0.239121 -0.264521)
							(end 0.254 -0.2286)
						)
						(arc
							(start 0.254 0.2286)
							(mid 0.239121 0.264521)
							(end 0.2032 0.2794)
						)
					)
					(width 0)
					(fill yes)
				)
			)
		)
	)
	(footprint ""
		(layer "B.Cu")
		(at 73.66 -13.589)
		(property "Reference" "C278"
			(at 0 0 0)
			(layer "B.SilkS")
			(hide yes)
			(effects
				(font
					(size 1.27 1.27)
				)
				(justify mirror)
			)
		)
		(property "Value" "SCD1U16V2KX-3GP"
			(at -1.1811 -2.7051 0)
			(unlocked yes)
			(layer "B.Fab")
			(hide yes)
			(effects
				(font
					(size 1.016 1.016)
					(thickness 0.1524)
				)
				(justify mirror)
			)
		)
		(property "Device Type" "C402H22"
			(at -1.1811 -4.2291 0)
			(unlocked yes)
			(layer "B.Fab")
			(hide yes)
			(effects
				(font
					(size 1.016 1.016)
					(thickness 0.1524)
				)
				(justify mirror)
			)
		)
		(duplicate_pad_numbers_are_jumpers no)
		(fp_rect
			(start 0.381 0.7366)
			(end -0.381 -0.7366)
			(stroke
				(width 0)
				(type default)
			)
			(fill no)
			(layer "B.CrtYd")
		)
		(fp_rect
			(start 0.381 0.7366)
			(end -0.381 -0.7366)
			(stroke
				(width 0)
				(type default)
			)
			(fill no)
			(layer "B.Fab")
		)
		(pad "1" smd custom
			(at 0 -0.4572 180)
			(size 0.1143 0.1143)
			(layers "B.Cu" "B.Mask" "B.Paste")
			(net "P2E_CPU_SAS_C_TX_DP2")
			(options
				(clearance outline)
				(anchor circle)
			)
			(primitives
				(gr_poly
					(pts
						(arc
							(start -0.254 0.1778)
							(mid -0.239121 0.213721)
							(end -0.2032 0.2286)
						)
						(arc
							(start 0.2032 0.2286)
							(mid 0.239121 0.213721)
							(end 0.254 0.1778)
						)
						(arc
							(start 0.254 -0.1778)
							(mid 0.239121 -0.213721)
							(end 0.2032 -0.2286)
						)
						(arc
							(start -0.2032 -0.2286)
							(mid -0.239121 -0.213721)
							(end -0.254 -0.1778)
						)
					)
					(width 0)
					(fill yes)
				)
			)
		)
		(pad "2" smd custom
			(at 0 0.4572 180)
			(size 0.1143 0.1143)
			(layers "B.Cu" "B.Mask" "B.Paste")
			(net "P2E_CPU_SAS_TX_DP2")
			(options
				(clearance outline)
				(anchor circle)
			)
			(primitives
				(gr_poly
					(pts
						(arc
							(start -0.254 0.1778)
							(mid -0.239121 0.213721)
							(end -0.2032 0.2286)
						)
						(arc
							(start 0.2032 0.2286)
							(mid 0.239121 0.213721)
							(end 0.254 0.1778)
						)
						(arc
							(start 0.254 -0.1778)
							(mid 0.239121 -0.213721)
							(end 0.2032 -0.2286)
						)
						(arc
							(start -0.2032 -0.2286)
							(mid -0.239121 -0.213721)
							(end -0.254 -0.1778)
						)
					)
					(width 0)
					(fill yes)
				)
			)
		)
	)
	(footprint ""
		(layer "B.Cu")
		(at 81.915 -63.246 180)
		(property "Reference" "R283"
			(at 0 0 0)
			(layer "B.SilkS")
			(hide yes)
			(effects
				(font
					(size 1.27 1.27)
				)
				(justify mirror)
			)
		)
		(property "Value" "0R2J-2-GP"
			(at -0.064008 -3.993896 180)
			(unlocked yes)
			(layer "B.Fab")
			(hide yes)
			(effects
				(font
					(size 1.016 1.016)
					(thickness 0.1524)
				)
				(justify mirror)
			)
		)
		(property "Device Type" "R402H16"
			(at -0.064008 -5.517896 180)
			(unlocked yes)
			(layer "B.Fab")
			(hide yes)
			(effects
				(font
					(size 1.016 1.016)
					(thickness 0.1524)
				)
				(justify mirror)
			)
		)
		(duplicate_pad_numbers_are_jumpers no)
		(fp_rect
			(start 0.381 0.8382)
			(end -0.381 -0.8382)
			(stroke
				(width 0)
				(type default)
			)
			(fill no)
			(layer "B.CrtYd")
		)
		(fp_rect
			(start 0.381 0.8382)
			(end -0.381 -0.8382)
			(stroke
				(width 0)
				(type default)
			)
			(fill no)
			(layer "B.Fab")
		)
		(pad "1" smd custom
			(at 0 -0.4318)
			(size 0.127 0.127)
			(layers "B.Cu" "B.Mask" "B.Paste")
			(net "SVID_CLK_R")
			(options
				(clearance outline)
				(anchor circle)
			)
			(primitives
				(gr_poly
					(pts
						(arc
							(start -0.2032 0.2794)
							(mid -0.239121 0.264521)
							(end -0.254 0.2286)
						)
						(arc
							(start -0.254 -0.2286)
							(mid -0.239121 -0.264521)
							(end -0.2032 -0.2794)
						)
						(arc
							(start 0.2032 -0.2794)
							(mid 0.239121 -0.264521)
							(end 0.254 -0.2286)
						)
						(arc
							(start 0.254 0.2286)
							(mid 0.239121 0.264521)
							(end 0.2032 0.2794)
						)
					)
					(width 0)
					(fill yes)
				)
			)
		)
		(pad "2" smd custom
			(at 0 0.4318)
			(size 0.127 0.127)
			(layers "B.Cu" "B.Mask" "B.Paste")
			(net "SVID_CPU_CLK")
			(options
				(clearance outline)
				(anchor circle)
			)
			(primitives
				(gr_poly
					(pts
						(arc
							(start -0.2032 0.2794)
							(mid -0.239121 0.264521)
							(end -0.254 0.2286)
						)
						(arc
							(start -0.254 -0.2286)
							(mid -0.239121 -0.264521)
							(end -0.2032 -0.2794)
						)
						(arc
							(start 0.2032 -0.2794)
							(mid 0.239121 -0.264521)
							(end 0.254 -0.2286)
						)
						(arc
							(start 0.254 0.2286)
							(mid 0.239121 0.264521)
							(end 0.2032 0.2794)
						)
					)
					(width 0)
					(fill yes)
				)
			)
		)
	)
	(footprint ""
		(layer "B.Cu")
		(at 18.923 -22.352 -90)
		(property "Reference" "PR101"
			(at 0 0 90)
			(layer "B.SilkS")
			(hide yes)
			(effects
				(font
					(size 1.27 1.27)
				)
				(justify mirror)
			)
		)
		(property "Value" "10KR2F-L1-GP"
			(at -1.7907 -1.1176 270)
			(unlocked yes)
			(layer "B.Fab")
			(hide yes)
			(effects
				(font
					(size 1.016 1.016)
					(thickness 0.1524)
				)
				(justify mirror)
			)
		)
		(property "Device Type" "R402H15"
			(at -1.7907 -2.6416 270)
			(unlocked yes)
			(layer "B.Fab")
			(hide yes)
			(effects
				(font
					(size 1.016 1.016)
					(thickness 0.1524)
				)
				(justify mirror)
			)
		)
		(duplicate_pad_numbers_are_jumpers no)
		(fp_rect
			(start 0.381 0.8382)
			(end -0.381 -0.8382)
			(stroke
				(width 0)
				(type default)
			)
			(fill no)
			(layer "B.CrtYd")
		)
		(fp_rect
			(start 0.381 0.8382)
			(end -0.381 -0.8382)
			(stroke
				(width 0)
				(type default)
			)
			(fill no)
			(layer "B.Fab")
		)
		(pad "1" smd custom
			(at 0 -0.4318 90)
			(size 0.127 0.127)
			(layers "B.Cu" "B.Mask" "B.Paste")
			(net "P3V3_STBY")
			(options
				(clearance outline)
				(anchor circle)
			)
			(primitives
				(gr_poly
					(pts
						(arc
							(start -0.2032 0.2794)
							(mid -0.239121 0.264521)
							(end -0.254 0.2286)
						)
						(arc
							(start -0.254 -0.2286)
							(mid -0.239121 -0.264521)
							(end -0.2032 -0.2794)
						)
						(arc
							(start 0.2032 -0.2794)
							(mid 0.239121 -0.264521)
							(end 0.254 -0.2286)
						)
						(arc
							(start 0.254 0.2286)
							(mid 0.239121 0.264521)
							(end 0.2032 0.2794)
						)
					)
					(width 0)
					(fill yes)
				)
			)
		)
		(pad "2" smd custom
			(at 0 0.4318 90)
			(size 0.127 0.127)
			(layers "B.Cu" "B.Mask" "B.Paste")
			(net "P1V0_EN")
			(options
				(clearance outline)
				(anchor circle)
			)
			(primitives
				(gr_poly
					(pts
						(arc
							(start -0.2032 0.2794)
							(mid -0.239121 0.264521)
							(end -0.254 0.2286)
						)
						(arc
							(start -0.254 -0.2286)
							(mid -0.239121 -0.264521)
							(end -0.2032 -0.2794)
						)
						(arc
							(start 0.2032 -0.2794)
							(mid 0.239121 -0.264521)
							(end 0.254 -0.2286)
						)
						(arc
							(start 0.254 0.2286)
							(mid 0.239121 0.264521)
							(end 0.2032 0.2794)
						)
					)
					(width 0)
					(fill yes)
				)
			)
		)
	)
	(footprint ""
		(layer "B.Cu")
		(at 91.7702 -41.5798 180)
		(property "Reference" "C178"
			(at 0 0 0)
			(layer "B.SilkS")
			(hide yes)
			(effects
				(font
					(size 1.27 1.27)
				)
				(justify mirror)
			)
		)
		(property "Value" "SC1U10V2KX-1GP"
			(at -1.1811 -2.7051 180)
			(unlocked yes)
			(layer "B.Fab")
			(hide yes)
			(effects
				(font
					(size 1.016 1.016)
					(thickness 0.1524)
				)
				(justify mirror)
			)
		)
		(property "Device Type" "C402H22"
			(at -1.1811 -4.2291 180)
			(unlocked yes)
			(layer "B.Fab")
			(hide yes)
			(effects
				(font
					(size 1.016 1.016)
					(thickness 0.1524)
				)
				(justify mirror)
			)
		)
		(duplicate_pad_numbers_are_jumpers no)
		(fp_rect
			(start 0.381 0.7366)
			(end -0.381 -0.7366)
			(stroke
				(width 0)
				(type default)
			)
			(fill no)
			(layer "B.CrtYd")
		)
		(fp_rect
			(start 0.381 0.7366)
			(end -0.381 -0.7366)
			(stroke
				(width 0)
				(type default)
			)
			(fill no)
			(layer "B.Fab")
		)
		(pad "1" smd custom
			(at 0 -0.4572)
			(size 0.1143 0.1143)
			(layers "B.Cu" "B.Mask" "B.Paste")
			(net "P1V8")
			(options
				(clearance outline)
				(anchor circle)
			)
			(primitives
				(gr_poly
					(pts
						(arc
							(start -0.254 0.1778)
							(mid -0.239121 0.213721)
							(end -0.2032 0.2286)
						)
						(arc
							(start 0.2032 0.2286)
							(mid 0.239121 0.213721)
							(end 0.254 0.1778)
						)
						(arc
							(start 0.254 -0.1778)
							(mid 0.239121 -0.213721)
							(end 0.2032 -0.2286)
						)
						(arc
							(start -0.2032 -0.2286)
							(mid -0.239121 -0.213721)
							(end -0.254 -0.1778)
						)
					)
					(width 0)
					(fill yes)
				)
			)
		)
		(pad "2" smd custom
			(at 0 0.4572)
			(size 0.1143 0.1143)
			(layers "B.Cu" "B.Mask" "B.Paste")
			(net "GND")
			(options
				(clearance outline)
				(anchor circle)
			)
			(primitives
				(gr_poly
					(pts
						(arc
							(start -0.254 0.1778)
							(mid -0.239121 0.213721)
							(end -0.2032 0.2286)
						)
						(arc
							(start 0.2032 0.2286)
							(mid 0.239121 0.213721)
							(end 0.254 0.1778)
						)
						(arc
							(start 0.254 -0.1778)
							(mid 0.239121 -0.213721)
							(end 0.2032 -0.2286)
						)
						(arc
							(start -0.2032 -0.2286)
							(mid -0.239121 -0.213721)
							(end -0.254 -0.1778)
						)
					)
					(width 0)
					(fill yes)
				)
			)
		)
	)
	(footprint ""
		(layer "B.Cu")
		(at 132.715 -27.305 -90)
		(property "Reference" "R34"
			(at 0 0 90)
			(layer "B.SilkS")
			(hide yes)
			(effects
				(font
					(size 1.27 1.27)
				)
				(justify mirror)
			)
		)
		(property "Value" "49D9R2F-GP"
			(at -0.064008 -3.993896 270)
			(unlocked yes)
			(layer "B.Fab")
			(hide yes)
			(effects
				(font
					(size 1.016 1.016)
					(thickness 0.1524)
				)
				(justify mirror)
			)
		)
		(property "Device Type" "R402H16"
			(at -0.064008 -5.517896 270)
			(unlocked yes)
			(layer "B.Fab")
			(hide yes)
			(effects
				(font
					(size 1.016 1.016)
					(thickness 0.1524)
				)
				(justify mirror)
			)
		)
		(duplicate_pad_numbers_are_jumpers no)
		(fp_rect
			(start 0.381 0.8382)
			(end -0.381 -0.8382)
			(stroke
				(width 0)
				(type default)
			)
			(fill no)
			(layer "B.CrtYd")
		)
		(fp_rect
			(start 0.381 0.8382)
			(end -0.381 -0.8382)
			(stroke
				(width 0)
				(type default)
			)
			(fill no)
			(layer "B.Fab")
		)
		(pad "1" smd custom
			(at 0 -0.4318 90)
			(size 0.127 0.127)
			(layers "B.Cu" "B.Mask" "B.Paste")
			(net "P1V0")
			(options
				(clearance outline)
				(anchor circle)
			)
			(primitives
				(gr_poly
					(pts
						(arc
							(start -0.2032 0.2794)
							(mid -0.239121 0.264521)
							(end -0.254 0.2286)
						)
						(arc
							(start -0.254 -0.2286)
							(mid -0.239121 -0.264521)
							(end -0.2032 -0.2794)
						)
						(arc
							(start 0.2032 -0.2794)
							(mid 0.239121 -0.264521)
							(end 0.254 -0.2286)
						)
						(arc
							(start 0.254 0.2286)
							(mid 0.239121 0.264521)
							(end 0.2032 0.2794)
						)
					)
					(width 0)
					(fill yes)
				)
			)
		)
		(pad "2" smd custom
			(at 0 0.4318 90)
			(size 0.127 0.127)
			(layers "B.Cu" "B.Mask" "B.Paste")
			(net "CPU_THERMTRIP#")
			(options
				(clearance outline)
				(anchor circle)
			)
			(primitives
				(gr_poly
					(pts
						(arc
							(start -0.2032 0.2794)
							(mid -0.239121 0.264521)
							(end -0.254 0.2286)
						)
						(arc
							(start -0.254 -0.2286)
							(mid -0.239121 -0.264521)
							(end -0.2032 -0.2794)
						)
						(arc
							(start 0.2032 -0.2794)
							(mid 0.239121 -0.264521)
							(end 0.254 -0.2286)
						)
						(arc
							(start 0.254 0.2286)
							(mid 0.239121 0.264521)
							(end 0.2032 0.2794)
						)
					)
					(width 0)
					(fill yes)
				)
			)
		)
	)
	(footprint ""
		(layer "B.Cu")
		(at 105.664 -27.321002)
		(property "Reference" "C240"
			(at 0 0 0)
			(layer "B.SilkS")
			(hide yes)
			(effects
				(font
					(size 1.27 1.27)
				)
				(justify mirror)
			)
		)
		(property "Value" "SC1U10V2KX-1GP"
			(at -1.1811 -2.7051 0)
			(unlocked yes)
			(layer "B.Fab")
			(hide yes)
			(effects
				(font
					(size 1.016 1.016)
					(thickness 0.1524)
				)
				(justify mirror)
			)
		)
		(property "Device Type" "C402H22"
			(at -1.1811 -4.2291 0)
			(unlocked yes)
			(layer "B.Fab")
			(hide yes)
			(effects
				(font
					(size 1.016 1.016)
					(thickness 0.1524)
				)
				(justify mirror)
			)
		)
		(duplicate_pad_numbers_are_jumpers no)
		(fp_rect
			(start 0.381 0.7366)
			(end -0.381 -0.7366)
			(stroke
				(width 0)
				(type default)
			)
			(fill no)
			(layer "B.CrtYd")
		)
		(fp_rect
			(start 0.381 0.7366)
			(end -0.381 -0.7366)
			(stroke
				(width 0)
				(type default)
			)
			(fill no)
			(layer "B.Fab")
		)
		(pad "1" smd custom
			(at 0 -0.4572 180)
			(size 0.1143 0.1143)
			(layers "B.Cu" "B.Mask" "B.Paste")
			(net "PV_VDDR")
			(options
				(clearance outline)
				(anchor circle)
			)
			(primitives
				(gr_poly
					(pts
						(arc
							(start -0.254 0.1778)
							(mid -0.239121 0.213721)
							(end -0.2032 0.2286)
						)
						(arc
							(start 0.2032 0.2286)
							(mid 0.239121 0.213721)
							(end 0.254 0.1778)
						)
						(arc
							(start 0.254 -0.1778)
							(mid 0.239121 -0.213721)
							(end 0.2032 -0.2286)
						)
						(arc
							(start -0.2032 -0.2286)
							(mid -0.239121 -0.213721)
							(end -0.254 -0.1778)
						)
					)
					(width 0)
					(fill yes)
				)
			)
		)
		(pad "2" smd custom
			(at 0 0.4572 180)
			(size 0.1143 0.1143)
			(layers "B.Cu" "B.Mask" "B.Paste")
			(net "GND")
			(options
				(clearance outline)
				(anchor circle)
			)
			(primitives
				(gr_poly
					(pts
						(arc
							(start -0.254 0.1778)
							(mid -0.239121 0.213721)
							(end -0.2032 0.2286)
						)
						(arc
							(start 0.2032 0.2286)
							(mid 0.239121 0.213721)
							(end 0.254 0.1778)
						)
						(arc
							(start 0.254 -0.1778)
							(mid 0.239121 -0.213721)
							(end 0.2032 -0.2286)
						)
						(arc
							(start -0.2032 -0.2286)
							(mid -0.239121 -0.213721)
							(end -0.254 -0.1778)
						)
					)
					(width 0)
					(fill yes)
				)
			)
		)
	)
)
